FILE_TYPE = CONNECTIVITY;
{Allegro Design Entry HDL 17.2-2016 S081 (4005846) 1/11/2022}
"PAGE_NUMBER" = 67;
0"NC";
1"PVDD11_S3_P0\g";
2"GND\g";
3"PVDD11_S3_P0\g";
4"GND\g";
5"GND\g";
6"GND\g";
7"PVDDCR_SOC_P0\g";
8"PVDDCR_SOC_P0\g";
9"GND\g";
10"PVDDCR_SOC_P0\g";
11"PVDDIO_P0\g";
12"GND\g";
13"GND\g";
14"PVDD18_S5_P0\g";
%"Q_CAP"
"1","(-10425,5850)","0","pure_quanta","I100";
;
LOCATION"C2154"
$SEC"1"
CDS_SEC"1"
MATERIAL"X6S"
TOLERANCE"20%"
VALUE"22UF"
PART_NUMBER"CH622KMEB02"
VOLTAGE"4V"
PACK_TYPE"C0402"
CDS_LIB"pure_quanta";
"B"
$PN"2"9;
"A"
$PN"1"8;
%"Q_CAP"
"1","(-9975,5050)","0","pure_quanta","I101";
;
LOCATION"C3894"
$SEC"1"
CDS_SEC"1"
MATERIAL"X6S"
TOLERANCE"20%"
VALUE"22UF"
PART_NUMBER"CH622KMEB02"
VOLTAGE"4V"
PACK_TYPE"C0402"
CDS_LIB"pure_quanta";
"B"
$PN"2"6;
"A"
$PN"1"10;
%"Q_CAP"
"1","(-9525,5050)","0","pure_quanta","I102";
;
LOCATION"C3895"
$SEC"1"
CDS_SEC"1"
MATERIAL"X6S"
TOLERANCE"20%"
VALUE"22UF"
PART_NUMBER"CH622KMEB02"
VOLTAGE"4V"
PACK_TYPE"C0402"
CDS_LIB"pure_quanta";
"B"
$PN"2"6;
"A"
$PN"1"10;
%"Q_CAP"
"1","(-9975,5850)","0","pure_quanta","I103";
;
LOCATION"C2157"
$SEC"1"
CDS_SEC"1"
MATERIAL"X6S"
TOLERANCE"20%"
VALUE"22UF"
PART_NUMBER"CH622KMEB02"
VOLTAGE"4V"
PACK_TYPE"C0402"
CDS_LIB"pure_quanta";
"B"
$PN"2"9;
"A"
$PN"1"8;
%"Q_CAP"
"1","(-9525,5850)","0","pure_quanta","I104";
;
LOCATION"C2159"
$SEC"1"
CDS_SEC"1"
MATERIAL"X6S"
TOLERANCE"20%"
VALUE"22UF"
PART_NUMBER"CH622KMEB02"
VOLTAGE"4V"
PACK_TYPE"C0402"
CDS_LIB"pure_quanta";
"B"
$PN"2"9;
"A"
$PN"1"8;
%"UNIVERSAL_GND"
"1","(-9125,4675)","0","pure_quanta_power","I105";
;
CDS_LIB"pure_quanta_power"
HDL_POWER"GND";
"A"6;
%"Q_CAP"
"1","(-9125,5050)","0","pure_quanta","I106";
;
LOCATION"C3896"
$SEC"1"
CDS_SEC"1"
MATERIAL"X6S"
TOLERANCE"20%"
VALUE"22UF"
PART_NUMBER"CH622KMEB02"
VOLTAGE"4V"
PACK_TYPE"C0402"
CDS_LIB"pure_quanta";
"B"
$PN"2"6;
"A"
$PN"1"10;
%"UNIVERSAL_GND"
"1","(-9125,5475)","0","pure_quanta_power","I107";
;
CDS_LIB"pure_quanta_power"
HDL_POWER"GND";
"A"9;
%"Q_CAP"
"1","(-9125,5850)","0","pure_quanta","I108";
;
LOCATION"C2161"
$SEC"1"
CDS_SEC"1"
MATERIAL"X6S"
TOLERANCE"20%"
VALUE"22UF"
PART_NUMBER"CH622KMEB02"
VOLTAGE"4V"
PACK_TYPE"C0402"
CDS_LIB"pure_quanta";
"B"
$PN"2"9;
"A"
$PN"1"8;
%"Q_CAP"
"1","(-11325,5850)","0","pure_quanta","I109";
;
LOCATION"C2147"
$SEC"1"
CDS_SEC"1"
MATERIAL"X6S"
TOLERANCE"20%"
VALUE"22UF"
PART_NUMBER"CH622KMEB02"
VOLTAGE"4V"
PACK_TYPE"C0402"
CDS_LIB"pure_quanta";
"B"
$PN"2"9;
"A"
$PN"1"8;
%"Q_CAP"
"1","(-13125,1600)","0","pure_quanta","I110";
;
LOCATION"C2133"
$SEC"1"
CDS_SEC"1"
MATERIAL"X6S"
TOLERANCE"20%"
VALUE"22UF"
PART_NUMBER"CH622KMEB02"
VOLTAGE"4V"
PACK_TYPE"C0402"
CDS_LIB"pure_quanta";
"B"
$PN"2"2;
"A"
$PN"1"1;
%"UNIVERSAL_POWER"
"1","(-13125,1875)","0","pure_quanta_power","I111";
;
HDL_POWER"PVDD11_S3_P0"
CDS_LIB"pure_quanta_power";
"A"1;
%"Q_CAP"
"1","(-12675,1600)","0","pure_quanta","I112";
;
LOCATION"C2138"
$SEC"1"
CDS_SEC"1"
MATERIAL"X6S"
TOLERANCE"20%"
VALUE"22UF"
PART_NUMBER"CH622KMEB02"
VOLTAGE"4V"
PACK_TYPE"C0402"
CDS_LIB"pure_quanta";
"B"
$PN"2"2;
"A"
$PN"1"1;
%"Q_CAP"
"1","(-13125,2350)","0","pure_quanta","I113";
;
LOCATION"C2132"
$SEC"1"
CDS_SEC"1"
MATERIAL"X6S"
TOLERANCE"20%"
VALUE"22UF"
PART_NUMBER"CH622KMEB02"
VOLTAGE"4V"
PACK_TYPE"C0402"
CDS_LIB"pure_quanta";
"B"
$PN"2"4;
"A"
$PN"1"3;
%"UNIVERSAL_POWER"
"1","(-13125,2625)","0","pure_quanta_power","I114";
;
HDL_POWER"PVDD11_S3_P0"
CDS_LIB"pure_quanta_power";
"A"3;
%"Q_CAP"
"1","(-12675,2350)","0","pure_quanta","I115";
;
LOCATION"C2137"
$SEC"1"
CDS_SEC"1"
MATERIAL"X6S"
TOLERANCE"20%"
VALUE"22UF"
PART_NUMBER"CH622KMEB02"
VOLTAGE"4V"
PACK_TYPE"C0402"
CDS_LIB"pure_quanta";
"B"
$PN"2"4;
"A"
$PN"1"3;
%"Q_CAP"
"1","(-12225,1600)","0","pure_quanta","I116";
;
LOCATION"C3890"
$SEC"1"
CDS_SEC"1"
MATERIAL"X6S"
TOLERANCE"20%"
VALUE"22UF"
PART_NUMBER"CH622KMEB02"
VOLTAGE"4V"
PACK_TYPE"C0402"
CDS_LIB"pure_quanta";
"B"
$PN"2"2;
"A"
$PN"1"1;
%"Q_CAP"
"1","(-11775,1600)","0","pure_quanta","I117";
;
LOCATION"C3891"
$SEC"1"
CDS_SEC"1"
MATERIAL"X6S"
TOLERANCE"20%"
VALUE"22UF"
PART_NUMBER"CH622KMEB02"
VOLTAGE"4V"
PACK_TYPE"C0402"
CDS_LIB"pure_quanta";
"B"
$PN"2"2;
"A"
$PN"1"1;
%"Q_CAP"
"1","(-11325,1600)","0","pure_quanta","I118";
;
LOCATION"C3892"
$SEC"1"
CDS_SEC"1"
MATERIAL"X6S"
TOLERANCE"20%"
VALUE"22UF"
PART_NUMBER"CH622KMEB02"
VOLTAGE"4V"
PACK_TYPE"C0402"
CDS_LIB"pure_quanta";
"B"
$PN"2"2;
"A"
$PN"1"1;
%"UNIVERSAL_GND"
"1","(-10875,1225)","0","pure_quanta_power","I119";
;
CDS_LIB"pure_quanta_power"
HDL_POWER"GND";
"A"2;
%"Q_CAP"
"1","(-10875,1600)","0","pure_quanta","I120";
;
LOCATION"C3893"
$SEC"1"
CDS_SEC"1"
MATERIAL"X6S"
TOLERANCE"20%"
VALUE"22UF"
PART_NUMBER"CH622KMEB02"
VOLTAGE"4V"
PACK_TYPE"C0402"
CDS_LIB"pure_quanta";
"B"
$PN"2"2;
"A"
$PN"1"1;
%"Q_CAP"
"1","(-12225,2350)","0","pure_quanta","I121";
;
LOCATION"C2142"
$SEC"1"
CDS_SEC"1"
MATERIAL"X6S"
TOLERANCE"20%"
VALUE"22UF"
PART_NUMBER"CH622KMEB02"
VOLTAGE"4V"
PACK_TYPE"C0402"
CDS_LIB"pure_quanta";
"B"
$PN"2"4;
"A"
$PN"1"3;
%"Q_CAP"
"1","(-11775,2350)","0","pure_quanta","I122";
;
LOCATION"C2146"
$SEC"1"
CDS_SEC"1"
MATERIAL"X6S"
TOLERANCE"20%"
VALUE"22UF"
PART_NUMBER"CH622KMEB02"
VOLTAGE"4V"
PACK_TYPE"C0402"
CDS_LIB"pure_quanta";
"B"
$PN"2"4;
"A"
$PN"1"3;
%"Q_CAP"
"1","(-11325,2350)","0","pure_quanta","I123";
;
LOCATION"C2150"
$SEC"1"
CDS_SEC"1"
MATERIAL"X6S"
TOLERANCE"20%"
VALUE"22UF"
PART_NUMBER"CH622KMEB02"
VOLTAGE"4V"
PACK_TYPE"C0402"
CDS_LIB"pure_quanta";
"B"
$PN"2"4;
"A"
$PN"1"3;
%"Q_CAP"
"1","(-10875,2350)","0","pure_quanta","I124";
;
LOCATION"C2153"
$SEC"1"
CDS_SEC"1"
MATERIAL"X6S"
TOLERANCE"20%"
VALUE"22UF"
PART_NUMBER"CH622KMEB02"
VOLTAGE"4V"
PACK_TYPE"C0402"
CDS_LIB"pure_quanta";
"B"
$PN"2"4;
"A"
$PN"1"3;
%"Q_CAP"
"1","(-10425,2350)","0","pure_quanta","I125";
;
LOCATION"C2156"
$SEC"1"
CDS_SEC"1"
MATERIAL"X6S"
TOLERANCE"20%"
VALUE"22UF"
PART_NUMBER"CH622KMEB02"
VOLTAGE"4V"
PACK_TYPE"C0402"
CDS_LIB"pure_quanta";
"B"
$PN"2"4;
"A"
$PN"1"3;
%"UNIVERSAL_GND"
"1","(-9125,1975)","0","pure_quanta_power","I126";
;
CDS_LIB"pure_quanta_power"
HDL_POWER"GND";
"A"4;
%"Q_CAP"
"1","(-9975,2350)","0","pure_quanta","I127";
;
LOCATION"C2158"
$SEC"1"
CDS_SEC"1"
MATERIAL"X6S"
TOLERANCE"20%"
VALUE"22UF"
PART_NUMBER"CH622KMEB02"
VOLTAGE"4V"
PACK_TYPE"C0402"
CDS_LIB"pure_quanta";
"B"
$PN"2"4;
"A"
$PN"1"3;
%"Q_CAP"
"1","(-9525,2350)","0","pure_quanta","I128";
;
LOCATION"C2160"
$SEC"1"
CDS_SEC"1"
MATERIAL"X6S"
TOLERANCE"20%"
VALUE"22UF"
PART_NUMBER"CH622KMEB02"
VOLTAGE"4V"
PACK_TYPE"C0402"
CDS_LIB"pure_quanta";
"B"
$PN"2"4;
"A"
$PN"1"3;
%"Q_CAP"
"1","(-9125,2350)","0","pure_quanta","I129";
;
LOCATION"C2162"
$SEC"1"
CDS_SEC"1"
MATERIAL"X6S"
TOLERANCE"20%"
VALUE"22UF"
PART_NUMBER"CH622KMEB02"
VOLTAGE"4V"
PACK_TYPE"C0402"
CDS_LIB"pure_quanta";
"B"
$PN"2"4;
"A"
$PN"1"3;
%"UNIVERSAL_GND"
"1","(-7250,3850)","0","pure_quanta_power","I130";
;
CDS_LIB"pure_quanta_power"
HDL_POWER"GND";
"A"13;
%"Q_CAP"
"1","(-8150,4200)","0","pure_quanta","I131";
;
LOCATION"C2163"
$SEC"1"
CDS_SEC"1"
MATERIAL"X6S"
TOLERANCE"20%"
VALUE"22UF"
PART_NUMBER"CH622KMEB02"
VOLTAGE"4V"
PACK_TYPE"C0402"
CDS_LIB"pure_quanta";
"B"
$PN"2"13;
"A"
$PN"1"14;
%"UNIVERSAL_POWER"
"1","(-8150,4475)","0","pure_quanta_power","I132";
;
HDL_POWER"PVDD18_S5_P0"
CDS_LIB"pure_quanta_power";
"A"14;
%"Q_CAP"
"1","(-7700,4200)","0","pure_quanta","I133";
;
LOCATION"C2164"
$SEC"1"
CDS_SEC"1"
MATERIAL"X6S"
TOLERANCE"20%"
VALUE"22UF"
PART_NUMBER"CH622KMEB02"
VOLTAGE"4V"
PACK_TYPE"C0402"
CDS_LIB"pure_quanta";
"B"
$PN"2"13;
"A"
$PN"1"14;
%"Q_CAP"
"1","(-7250,4200)","0","pure_quanta","I134";
;
LOCATION"C3897"
$SEC"1"
CDS_SEC"1"
MATERIAL"X6S"
TOLERANCE"20%"
VALUE"22UF"
PART_NUMBER"CH622KMEB02"
VOLTAGE"4V"
PACK_TYPE"C0402"
CDS_LIB"pure_quanta";
"B"
$PN"2"13;
"A"
$PN"1"14;
%"Q_CAP"
"1","(-8200,5950)","0","pure_quanta","I135";
;
LOCATION"C2131"
$SEC"1"
CDS_SEC"1"
MATERIAL"X6S"
TOLERANCE"20%"
VALUE"22UF"
PART_NUMBER"CH622KMEB02"
VOLTAGE"4V"
PACK_TYPE"C0402"
CDS_LIB"pure_quanta";
"B"
$PN"2"12;
"A"
$PN"1"11;
%"Q_CAP"
"1","(-7750,5950)","0","pure_quanta","I136";
;
LOCATION"C2136"
$SEC"1"
CDS_SEC"1"
MATERIAL"X6S"
TOLERANCE"20%"
VALUE"22UF"
PART_NUMBER"CH622KMEB02"
VOLTAGE"4V"
PACK_TYPE"C0402"
CDS_LIB"pure_quanta";
"B"
$PN"2"12;
"A"
$PN"1"11;
%"Q_CAP"
"1","(-7300,5950)","0","pure_quanta","I137";
;
LOCATION"C2141"
$SEC"1"
CDS_SEC"1"
MATERIAL"X6S"
TOLERANCE"20%"
VALUE"22UF"
PART_NUMBER"CH622KMEB02"
VOLTAGE"4V"
PACK_TYPE"C0402"
CDS_LIB"pure_quanta";
"B"
$PN"2"12;
"A"
$PN"1"11;
%"Q_CAP"
"1","(-6850,5950)","0","pure_quanta","I138";
;
LOCATION"C2145"
$SEC"1"
CDS_SEC"1"
MATERIAL"X6S"
TOLERANCE"20%"
VALUE"22UF"
PART_NUMBER"CH622KMEB02"
VOLTAGE"4V"
PACK_TYPE"C0402"
CDS_LIB"pure_quanta";
"B"
$PN"2"12;
"A"
$PN"1"11;
%"Q_CAP"
"1","(-6400,5950)","0","pure_quanta","I139";
;
LOCATION"C2149"
$SEC"1"
CDS_SEC"1"
MATERIAL"X6S"
TOLERANCE"20%"
VALUE"22UF"
PART_NUMBER"CH622KMEB02"
VOLTAGE"4V"
PACK_TYPE"C0402"
CDS_LIB"pure_quanta";
"B"
$PN"2"12;
"A"
$PN"1"11;
%"UNIVERSAL_POWER"
"1","(-8200,6225)","0","pure_quanta_power","I140";
;
HDL_POWER"PVDDIO_P0"
CDS_LIB"pure_quanta_power";
"A"11;
%"Q_CAP"
"1","(-5950,5950)","0","pure_quanta","I141";
;
LOCATION"C3898"
$SEC"1"
CDS_SEC"1"
MATERIAL"X6S"
TOLERANCE"20%"
VALUE"22UF"
PART_NUMBER"CH622KMEB02"
VOLTAGE"4V"
PACK_TYPE"C0402"
CDS_LIB"pure_quanta";
"B"
$PN"2"12;
"A"
$PN"1"11;
%"UNIVERSAL_GND"
"1","(-5500,5600)","0","pure_quanta_power","I142";
;
CDS_LIB"pure_quanta_power"
HDL_POWER"GND";
"A"12;
%"Q_CAP"
"1","(-5500,5950)","0","pure_quanta","I143";
;
LOCATION"C3899"
$SEC"1"
CDS_SEC"1"
MATERIAL"X6S"
TOLERANCE"20%"
VALUE"22UF"
PART_NUMBER"CH622KMEB02"
VOLTAGE"4V"
PACK_TYPE"C0402"
CDS_LIB"pure_quanta";
"B"
$PN"2"12;
"A"
$PN"1"11;
%"UNIVERSAL_GND"
"1","(-12700,3900)","0","pure_quanta_power","I82";
;
CDS_LIB"pure_quanta_power"
HDL_POWER"GND";
"A"5;
%"Q_CAP"
"1","(-13100,4275)","0","pure_quanta","I83";
;
LOCATION"C3888"
$SEC"1"
CDS_SEC"1"
MATERIAL"X6S"
TOLERANCE"20%"
VALUE"22UF"
PART_NUMBER"CH622KMEB02"
VOLTAGE"4V"
PACK_TYPE"C0402"
CDS_LIB"pure_quanta";
"B"
$PN"2"5;
"A"
$PN"1"7;
%"UNIVERSAL_POWER"
"1","(-13100,4550)","0","pure_quanta_power","I84";
;
HDL_POWER"PVDDCR_SOC_P0"
CDS_LIB"pure_quanta_power";
"A"7;
%"Q_CAP"
"1","(-13125,5050)","0","pure_quanta","I85";
;
LOCATION"C2130"
$SEC"1"
CDS_SEC"1"
MATERIAL"X6S"
TOLERANCE"20%"
VALUE"22UF"
PART_NUMBER"CH622KMEB02"
VOLTAGE"4V"
PACK_TYPE"C0402"
CDS_LIB"pure_quanta";
"B"
$PN"2"6;
"A"
$PN"1"10;
%"Q_CAP"
"1","(-12700,4275)","0","pure_quanta","I86";
;
LOCATION"C3889"
$SEC"1"
CDS_SEC"1"
MATERIAL"X6S"
TOLERANCE"20%"
VALUE"22UF"
PART_NUMBER"CH622KMEB02"
VOLTAGE"4V"
PACK_TYPE"C0402"
CDS_LIB"pure_quanta";
"B"
$PN"2"5;
"A"
$PN"1"7;
%"Q_CAP"
"1","(-12675,5050)","0","pure_quanta","I87";
;
LOCATION"C2135"
$SEC"1"
CDS_SEC"1"
MATERIAL"X6S"
TOLERANCE"20%"
VALUE"22UF"
PART_NUMBER"CH622KMEB02"
VOLTAGE"4V"
PACK_TYPE"C0402"
CDS_LIB"pure_quanta";
"B"
$PN"2"6;
"A"
$PN"1"10;
%"UNIVERSAL_POWER"
"1","(-13125,5325)","0","pure_quanta_power","I88";
;
HDL_POWER"PVDDCR_SOC_P0"
CDS_LIB"pure_quanta_power";
"A"10;
%"Q_CAP"
"1","(-13125,5850)","0","pure_quanta","I89";
;
LOCATION"C2129"
$SEC"1"
CDS_SEC"1"
MATERIAL"X6S"
TOLERANCE"20%"
VALUE"22UF"
PART_NUMBER"CH622KMEB02"
VOLTAGE"4V"
PACK_TYPE"C0402"
CDS_LIB"pure_quanta";
"B"
$PN"2"9;
"A"
$PN"1"8;
%"Q_CAP"
"1","(-12675,5850)","0","pure_quanta","I90";
;
LOCATION"C2134"
$SEC"1"
CDS_SEC"1"
MATERIAL"X6S"
TOLERANCE"20%"
VALUE"22UF"
PART_NUMBER"CH622KMEB02"
VOLTAGE"4V"
PACK_TYPE"C0402"
CDS_LIB"pure_quanta";
"B"
$PN"2"9;
"A"
$PN"1"8;
%"UNIVERSAL_POWER"
"1","(-13125,6125)","0","pure_quanta_power","I91";
;
HDL_POWER"PVDDCR_SOC_P0"
CDS_LIB"pure_quanta_power";
"A"8;
%"Q_CAP"
"1","(-12225,5050)","0","pure_quanta","I92";
;
LOCATION"C2140"
$SEC"1"
CDS_SEC"1"
MATERIAL"X6S"
TOLERANCE"20%"
VALUE"22UF"
PART_NUMBER"CH622KMEB02"
VOLTAGE"4V"
PACK_TYPE"C0402"
CDS_LIB"pure_quanta";
"B"
$PN"2"6;
"A"
$PN"1"10;
%"Q_CAP"
"1","(-11775,5050)","0","pure_quanta","I93";
;
LOCATION"C2144"
$SEC"1"
CDS_SEC"1"
MATERIAL"X6S"
TOLERANCE"20%"
VALUE"22UF"
PART_NUMBER"CH622KMEB02"
VOLTAGE"4V"
PACK_TYPE"C0402"
CDS_LIB"pure_quanta";
"B"
$PN"2"6;
"A"
$PN"1"10;
%"Q_CAP"
"1","(-11325,5050)","0","pure_quanta","I94";
;
LOCATION"C2148"
$SEC"1"
CDS_SEC"1"
MATERIAL"X6S"
TOLERANCE"20%"
VALUE"22UF"
PART_NUMBER"CH622KMEB02"
VOLTAGE"4V"
PACK_TYPE"C0402"
CDS_LIB"pure_quanta";
"B"
$PN"2"6;
"A"
$PN"1"10;
%"Q_CAP"
"1","(-12225,5850)","0","pure_quanta","I95";
;
LOCATION"C2139"
$SEC"1"
CDS_SEC"1"
MATERIAL"X6S"
TOLERANCE"20%"
VALUE"22UF"
PART_NUMBER"CH622KMEB02"
VOLTAGE"4V"
PACK_TYPE"C0402"
CDS_LIB"pure_quanta";
"B"
$PN"2"9;
"A"
$PN"1"8;
%"Q_CAP"
"1","(-11775,5850)","0","pure_quanta","I96";
;
LOCATION"C2143"
$SEC"1"
CDS_SEC"1"
MATERIAL"X6S"
TOLERANCE"20%"
VALUE"22UF"
PART_NUMBER"CH622KMEB02"
VOLTAGE"4V"
PACK_TYPE"C0402"
CDS_LIB"pure_quanta";
"B"
$PN"2"9;
"A"
$PN"1"8;
%"Q_CAP"
"1","(-10875,5050)","0","pure_quanta","I97";
;
LOCATION"C2152"
$SEC"1"
CDS_SEC"1"
MATERIAL"X6S"
TOLERANCE"20%"
VALUE"22UF"
PART_NUMBER"CH622KMEB02"
VOLTAGE"4V"
PACK_TYPE"C0402"
CDS_LIB"pure_quanta";
"B"
$PN"2"6;
"A"
$PN"1"10;
%"Q_CAP"
"1","(-10425,5050)","0","pure_quanta","I98";
;
LOCATION"C2155"
$SEC"1"
CDS_SEC"1"
MATERIAL"X6S"
TOLERANCE"20%"
VALUE"22UF"
PART_NUMBER"CH622KMEB02"
VOLTAGE"4V"
PACK_TYPE"C0402"
CDS_LIB"pure_quanta";
"B"
$PN"2"6;
"A"
$PN"1"10;
%"Q_CAP"
"1","(-10875,5850)","0","pure_quanta","I99";
;
LOCATION"C2151"
$SEC"1"
CDS_SEC"1"
MATERIAL"X6S"
TOLERANCE"20%"
VALUE"22UF"
PART_NUMBER"CH622KMEB02"
VOLTAGE"4V"
PACK_TYPE"C0402"
CDS_LIB"pure_quanta";
"B"
$PN"2"9;
"A"
$PN"1"8;
END.
